(kicad_pcb
	(version 20260206)
	(generator "pcbnew")
	(generator_version "10.0")
	(general
		(thickness 1.6)
		(legacy_teardrops no)
	)
	(paper "A4")
	(title_block
		(title "v2-pdb — ms_pdb_v2.brd")
		(comment 1 "Open CloudServer (Microsoft) / footprints 165-172 of 348")
	)
	(layers
		(0 "F.Cu" signal "TOP")
		(4 "In1.Cu" signal "GND")
		(6 "In2.Cu" signal "IN1")
		(8 "In3.Cu" signal "VCC")
		(10 "In4.Cu" signal "VCC1")
		(12 "In5.Cu" signal "IN2")
		(14 "In6.Cu" signal "GND1")
		(2 "B.Cu" signal "BOTTOM")
		(9 "F.Adhes" user "F.Adhesive")
		(11 "B.Adhes" user "B.Adhesive")
		(13 "F.Paste" user "Package Geometry/Pastemask Top")
		(15 "B.Paste" user "Package Geometry/Pastemask Bottom")
		(5 "F.SilkS" user "Ref Des/Silkscreen Top")
		(7 "B.SilkS" user "Ref Des/Silkscreen Bottom")
		(1 "F.Mask" user "Board Geometry/Soldermask Top")
		(3 "B.Mask" user "Board Geometry/Soldermask Bottom")
		(17 "Dwgs.User" user "User.Drawings")
		(19 "Cmts.User" user "User.Comments")
		(21 "Eco1.User" user "User.Eco1")
		(23 "Eco2.User" user "User.Eco2")
		(25 "Edge.Cuts" user "Board Geometry/Outline")
		(27 "Margin" user)
		(31 "F.CrtYd" user "Package Geometry/Place Bound Top")
		(29 "B.CrtYd" user "Package Geometry/Place Bound Bottom")
		(35 "F.Fab" user "Ref Des/Assembly Top")
		(33 "B.Fab" user "Ref Des/Assembly Bottom")
	)
	(footprint ""
		(layer "F.Cu")
		(at 77.254354 -18.749772 -90)
		(property "Reference" "C3"
			(at -1.75133 0.09906 90)
			(unlocked yes)
			(layer "F.SilkS")
			(effects
				(font
					(size 0.7874 0.5842)
					(thickness 0.1524)
				)
				(justify left)
			)
		)
		(property "Value" ""
			(at 0 0 270)
			(layer "F.Fab")
			(effects
				(font
					(size 1.27 1.27)
				)
			)
		)
		(duplicate_pad_numbers_are_jumpers no)
		(fp_line
			(start -0.7874 0.4064)
			(end -0.7874 -0.4064)
			(stroke
				(width 0.1524)
				(type default)
			)
			(layer "F.SilkS")
		)
		(fp_line
			(start 0.7874 0.4064)
			(end -0.7874 0.4064)
			(stroke
				(width 0.1524)
				(type default)
			)
			(layer "F.SilkS")
		)
		(fp_line
			(start 0 0.381)
			(end 0 -0.381)
			(stroke
				(width 0.1524)
				(type default)
			)
			(layer "F.SilkS")
		)
		(fp_line
			(start -0.7874 -0.4064)
			(end 0.7874 -0.4064)
			(stroke
				(width 0.1524)
				(type default)
			)
			(layer "F.SilkS")
		)
		(fp_line
			(start 0.7874 -0.4064)
			(end 0.7874 0.4064)
			(stroke
				(width 0.1524)
				(type default)
			)
			(layer "F.SilkS")
		)
		(fp_poly
			(pts
				(xy -0.5334 0.254) (xy -0.635 0.254) (xy -0.635 0.2286) (xy -0.635 -0.254) (xy -0.5334 -0.254) (xy -0.5334 -0.2794)
				(xy 0.5334 -0.2794) (xy 0.5334 -0.254) (xy 0.635 -0.254) (xy 0.635 0.254) (xy 0.5334 0.254) (xy 0.5334 0.2794)
				(xy -0.508 0.2794) (xy -0.5334 0.2794)
			)
			(stroke
				(width 0)
				(type default)
			)
			(fill no)
			(layer "F.CrtYd")
		)
		(pad "1" smd rect
			(at 0.40005 0 270)
			(size 0.4572 0.508)
			(layers "F.Cu" "F.Mask" "F.Paste")
			(net "P12V")
		)
		(pad "2" smd rect
			(at -0.40005 0 270)
			(size 0.4572 0.508)
			(layers "F.Cu" "F.Mask" "F.Paste")
			(net "GND")
		)
	)
	(footprint ""
		(layer "F.Cu")
		(at 50.417984 -217.485976 180)
		(property "Reference" "CE11"
			(at -4.932426 0.531114 0)
			(unlocked yes)
			(layer "F.SilkS")
			(effects
				(font
					(size 0.7874 0.5842)
					(thickness 0.1524)
				)
				(justify left)
			)
		)
		(property "Value" ""
			(at 0 0 180)
			(layer "F.Fab")
			(effects
				(font
					(size 1.27 1.27)
				)
			)
		)
		(duplicate_pad_numbers_are_jumpers no)
		(fp_line
			(start 0 -4.2672)
			(end 0 4.2672)
			(stroke
				(width 0.1524)
				(type default)
			)
			(layer "F.SilkS")
		)
		(fp_circle
			(center 0 0)
			(end -4.2672 0)
			(stroke
				(width 0.1524)
				(type default)
			)
			(fill no)
			(layer "F.SilkS")
		)
		(fp_poly
			(pts
				(arc
					(start 0 -4.2672)
					(mid 4.2672 0)
					(end 0 4.2672)
				)
			)
			(stroke
				(width 0)
				(type default)
			)
			(fill yes)
			(layer "F.SilkS")
		)
		(fp_poly
			(pts
				(xy -2.5146 -0.762) (xy -0.9906 -0.762) (xy -0.9906 0.762) (xy -2.5146 0.762)
			)
			(stroke
				(width 0)
				(type default)
			)
			(fill no)
			(layer "B.CrtYd")
		)
		(fp_poly
			(pts
				(arc
					(start 1.7526 0.762)
					(mid 2.291415 -0.538815)
					(end 0.9906 0)
				)
				(arc
					(start 0.9906 0.0254)
					(mid 1.206345 0.546255)
					(end 1.7272 0.762)
				)
			)
			(stroke
				(width 0)
				(type default)
			)
			(fill no)
			(layer "B.CrtYd")
		)
		(fp_poly
			(pts
				(arc
					(start -4.2672 0)
					(mid 4.2672 0)
					(end -4.2672 0)
				)
			)
			(stroke
				(width 0)
				(type default)
			)
			(fill no)
			(layer "F.CrtYd")
		)
		(fp_circle
			(center 0 0)
			(end -4.2672 0)
			(stroke
				(width 0.1)
				(type default)
			)
			(fill no)
			(layer "F.Fab")
		)
		(fp_text user "+"
			(at -6.029198 -1.261618 180)
			(unlocked yes)
			(layer "F.SilkS")
			(effects
				(font
					(size 1.905 1.4224)
					(thickness 0.1524)
				)
				(justify left)
			)
		)
		(fp_text user "+"
			(at -5.6642 -0.34925 180)
			(unlocked yes)
			(layer "F.Fab")
			(effects
				(font
					(size 1.905 1.4224)
					(thickness 0.000001)
				)
				(justify left)
			)
		)
		(pad "1" thru_hole rect
			(at -1.75006 0 180)
			(size 1.397 1.397)
			(drill 0.9144)
			(layers "*.Cu" "*.Mask")
			(remove_unused_layers no)
			(net "P12V")
			(clearance 0.0127)
			(thermal_gap 0.0127)
			(padstack
				(mode front_inner_back)
				(layer "Inner"
					(shape circle)
					(size 1.397 1.397)
					(clearance 0.0127)
				)
				(layer "B.Cu"
					(shape rect)
					(size 1.397 1.397)
					(clearance 0.0127)
				)
			)
		)
		(pad "2" thru_hole circle
			(at 1.75006 0 180)
			(size 1.397 1.397)
			(drill 0.9144)
			(layers "*.Cu" "*.Mask")
			(remove_unused_layers no)
			(net "GND")
			(clearance 0.0127)
			(thermal_gap 0.0127)
		)
	)
	(footprint ""
		(layer "F.Cu")
		(at 21.453602 -179.957984)
		(property "Reference" "C92"
			(at -1.182116 -1.317752 0)
			(unlocked yes)
			(layer "F.SilkS")
			(effects
				(font
					(size 0.7874 0.5842)
					(thickness 0.1524)
				)
			)
		)
		(property "Value" ""
			(at 0 0 0)
			(layer "F.Fab")
			(effects
				(font
					(size 1.27 1.27)
				)
			)
		)
		(duplicate_pad_numbers_are_jumpers no)
		(fp_line
			(start -1.2954 -0.5842)
			(end 1.2954 -0.5842)
			(stroke
				(width 0.1524)
				(type default)
			)
			(layer "F.SilkS")
		)
		(fp_line
			(start -1.2954 0.5842)
			(end -1.2954 -0.5842)
			(stroke
				(width 0.1524)
				(type default)
			)
			(layer "F.SilkS")
		)
		(fp_line
			(start 0 -0.5842)
			(end 0 0.5842)
			(stroke
				(width 0.1524)
				(type default)
			)
			(layer "F.SilkS")
		)
		(fp_line
			(start 1.2954 -0.5842)
			(end 1.2954 0.5842)
			(stroke
				(width 0.1524)
				(type default)
			)
			(layer "F.SilkS")
		)
		(fp_line
			(start 1.2954 0.5842)
			(end -1.2954 0.5842)
			(stroke
				(width 0.1524)
				(type default)
			)
			(layer "F.SilkS")
		)
		(fp_poly
			(pts
				(xy 0.8636 -0.4572) (xy 0.8636 -0.3556) (xy 1.143 -0.3556) (xy 1.143 0.3556) (xy 0.8636 0.3556)
				(xy 0.8636 0.4572) (xy -0.8636 0.4572) (xy -0.8636 0.3556) (xy -1.143 0.3556) (xy -1.143 -0.3556)
				(xy -0.8636 -0.3556) (xy -0.8636 -0.4572)
			)
			(stroke
				(width 0)
				(type default)
			)
			(fill no)
			(layer "F.CrtYd")
		)
		(fp_line
			(start -0.884936 -0.504952)
			(end 0.884936 -0.504952)
			(stroke
				(width 0.1)
				(type default)
			)
			(layer "F.Fab")
		)
		(fp_line
			(start -0.884936 0.504952)
			(end -0.884936 -0.504952)
			(stroke
				(width 0.1)
				(type default)
			)
			(layer "F.Fab")
		)
		(fp_line
			(start 0.884936 -0.504952)
			(end 0.884936 0.504952)
			(stroke
				(width 0.1)
				(type default)
			)
			(layer "F.Fab")
		)
		(fp_line
			(start 0.884936 0.504952)
			(end -0.884936 0.504952)
			(stroke
				(width 0.1)
				(type default)
			)
			(layer "F.Fab")
		)
		(pad "1" smd rect
			(at 0.7366 0 90)
			(size 0.7112 0.8128)
			(layers "F.Cu" "F.Mask" "F.Paste")
			(net "N42263600")
		)
		(pad "2" smd rect
			(at -0.7366 0 90)
			(size 0.7112 0.8128)
			(layers "F.Cu" "F.Mask" "F.Paste")
			(net "GND")
		)
	)
	(footprint ""
		(layer "F.Cu")
		(at 72.559164 -259.450078 90)
		(property "Reference" "C48"
			(at -4.374134 -0.046482 90)
			(unlocked yes)
			(layer "F.SilkS")
			(effects
				(font
					(size 0.7874 0.5842)
					(thickness 0.1524)
				)
				(justify left)
			)
		)
		(property "Value" ""
			(at 0 0 90)
			(layer "F.Fab")
			(effects
				(font
					(size 1.27 1.27)
				)
			)
		)
		(duplicate_pad_numbers_are_jumpers no)
		(fp_line
			(start 0.7874 -0.4064)
			(end 0.7874 0.4064)
			(stroke
				(width 0.1524)
				(type default)
			)
			(layer "F.SilkS")
		)
		(fp_line
			(start -0.7874 -0.4064)
			(end 0.7874 -0.4064)
			(stroke
				(width 0.1524)
				(type default)
			)
			(layer "F.SilkS")
		)
		(fp_line
			(start 0 0.381)
			(end 0 -0.381)
			(stroke
				(width 0.1524)
				(type default)
			)
			(layer "F.SilkS")
		)
		(fp_line
			(start 0.7874 0.4064)
			(end -0.7874 0.4064)
			(stroke
				(width 0.1524)
				(type default)
			)
			(layer "F.SilkS")
		)
		(fp_line
			(start -0.7874 0.4064)
			(end -0.7874 -0.4064)
			(stroke
				(width 0.1524)
				(type default)
			)
			(layer "F.SilkS")
		)
		(fp_poly
			(pts
				(xy -0.5334 0.254) (xy -0.635 0.254) (xy -0.635 0.2286) (xy -0.635 -0.254) (xy -0.5334 -0.254) (xy -0.5334 -0.2794)
				(xy 0.5334 -0.2794) (xy 0.5334 -0.254) (xy 0.635 -0.254) (xy 0.635 0.254) (xy 0.5334 0.254) (xy 0.5334 0.2794)
				(xy -0.508 0.2794) (xy -0.5334 0.2794)
			)
			(stroke
				(width 0)
				(type default)
			)
			(fill no)
			(layer "F.CrtYd")
		)
		(pad "1" smd rect
			(at 0.40005 0 90)
			(size 0.4572 0.508)
			(layers "F.Cu" "F.Mask" "F.Paste")
			(net "P12V")
		)
		(pad "2" smd rect
			(at -0.40005 0 90)
			(size 0.4572 0.508)
			(layers "F.Cu" "F.Mask" "F.Paste")
			(net "GND")
		)
	)
	(footprint ""
		(layer "F.Cu")
		(at 75.10145 -393.452604 90)
		(property "Reference" "C69"
			(at 1.084834 0.084582 90)
			(unlocked yes)
			(layer "F.SilkS")
			(effects
				(font
					(size 0.7874 0.5842)
					(thickness 0.1524)
				)
				(justify left)
			)
		)
		(property "Value" ""
			(at 0 0 90)
			(layer "F.Fab")
			(effects
				(font
					(size 1.27 1.27)
				)
			)
		)
		(duplicate_pad_numbers_are_jumpers no)
		(fp_line
			(start 0.7874 -0.4064)
			(end 0.7874 0.4064)
			(stroke
				(width 0.1524)
				(type default)
			)
			(layer "F.SilkS")
		)
		(fp_line
			(start -0.7874 -0.4064)
			(end 0.7874 -0.4064)
			(stroke
				(width 0.1524)
				(type default)
			)
			(layer "F.SilkS")
		)
		(fp_line
			(start 0 0.381)
			(end 0 -0.381)
			(stroke
				(width 0.1524)
				(type default)
			)
			(layer "F.SilkS")
		)
		(fp_line
			(start 0.7874 0.4064)
			(end -0.7874 0.4064)
			(stroke
				(width 0.1524)
				(type default)
			)
			(layer "F.SilkS")
		)
		(fp_line
			(start -0.7874 0.4064)
			(end -0.7874 -0.4064)
			(stroke
				(width 0.1524)
				(type default)
			)
			(layer "F.SilkS")
		)
		(fp_poly
			(pts
				(xy -0.5334 0.254) (xy -0.635 0.254) (xy -0.635 0.2286) (xy -0.635 -0.254) (xy -0.5334 -0.254) (xy -0.5334 -0.2794)
				(xy 0.5334 -0.2794) (xy 0.5334 -0.254) (xy 0.635 -0.254) (xy 0.635 0.254) (xy 0.5334 0.254) (xy 0.5334 0.2794)
				(xy -0.508 0.2794) (xy -0.5334 0.2794)
			)
			(stroke
				(width 0)
				(type default)
			)
			(fill no)
			(layer "F.CrtYd")
		)
		(pad "1" smd rect
			(at 0.40005 0 90)
			(size 0.4572 0.508)
			(layers "F.Cu" "F.Mask" "F.Paste")
			(net "P12V")
		)
		(pad "2" smd rect
			(at -0.40005 0 90)
			(size 0.4572 0.508)
			(layers "F.Cu" "F.Mask" "F.Paste")
			(net "GND")
		)
	)
	(footprint ""
		(layer "F.Cu")
		(at 21.162518 -448.10426 180)
		(property "Reference" "C89"
			(at -0.406146 -6.902958 0)
			(unlocked yes)
			(layer "F.SilkS")
			(effects
				(font
					(size 0.7874 0.5842)
					(thickness 0.1524)
				)
				(justify left)
			)
		)
		(property "Value" ""
			(at 0 0 180)
			(layer "F.Fab")
			(effects
				(font
					(size 1.27 1.27)
				)
			)
		)
		(duplicate_pad_numbers_are_jumpers no)
		(fp_line
			(start 1.905 0.8636)
			(end -1.905 0.8636)
			(stroke
				(width 0.1524)
				(type default)
			)
			(layer "F.SilkS")
		)
		(fp_line
			(start 1.905 -0.8636)
			(end 1.905 0.8636)
			(stroke
				(width 0.1524)
				(type default)
			)
			(layer "F.SilkS")
		)
		(fp_line
			(start 0 0.8382)
			(end 0 -0.8382)
			(stroke
				(width 0.1524)
				(type default)
			)
			(layer "F.SilkS")
		)
		(fp_line
			(start -1.905 0.8636)
			(end -1.905 -0.8636)
			(stroke
				(width 0.1524)
				(type default)
			)
			(layer "F.SilkS")
		)
		(fp_line
			(start -1.905 -0.8636)
			(end 1.905 -0.8636)
			(stroke
				(width 0.1524)
				(type default)
			)
			(layer "F.SilkS")
		)
		(fp_rect
			(start -1.524 0.7366)
			(end 1.524 -0.7366)
			(stroke
				(width 0)
				(type default)
			)
			(fill no)
			(layer "F.CrtYd")
		)
		(pad "1" smd rect
			(at 0.94996 0 180)
			(size 1.1176 1.3716)
			(layers "F.Cu" "F.Mask" "F.Paste")
			(net "P3V3_BUF")
		)
		(pad "2" smd rect
			(at -0.94996 0 180)
			(size 1.1176 1.3716)
			(layers "F.Cu" "F.Mask" "F.Paste")
			(net "GND")
		)
	)
	(footprint ""
		(layer "F.Cu")
		(at 16.348964 -336.728562)
		(property "Reference" "U1"
			(at -2.1082 -3.165348 0)
			(unlocked yes)
			(layer "F.SilkS")
			(effects
				(font
					(size 0.7874 0.5842)
					(thickness 0.1524)
				)
				(justify left)
			)
		)
		(property "Value" ""
			(at 0 0 0)
			(layer "F.Fab")
			(effects
				(font
					(size 1.27 1.27)
				)
			)
		)
		(duplicate_pad_numbers_are_jumpers no)
		(fp_line
			(start -1.8288 -2.500122)
			(end -1.8288 2.500122)
			(stroke
				(width 0.1524)
				(type default)
			)
			(layer "F.SilkS")
		)
		(fp_line
			(start -1.8288 2.500122)
			(end 1.8288 2.500122)
			(stroke
				(width 0.1524)
				(type default)
			)
			(layer "F.SilkS")
		)
		(fp_line
			(start -1.077722 -2.500122)
			(end -1.8288 -2.500122)
			(stroke
				(width 0.1524)
				(type default)
			)
			(layer "F.SilkS")
		)
		(fp_line
			(start 0 -1.4224)
			(end -1.077722 -2.500122)
			(stroke
				(width 0.1524)
				(type default)
			)
			(layer "F.SilkS")
		)
		(fp_line
			(start 1.077722 -2.500122)
			(end 0 -1.4224)
			(stroke
				(width 0.1524)
				(type default)
			)
			(layer "F.SilkS")
		)
		(fp_line
			(start 1.8288 -2.500122)
			(end 1.077722 -2.500122)
			(stroke
				(width 0.1524)
				(type default)
			)
			(layer "F.SilkS")
		)
		(fp_line
			(start 1.8288 2.500122)
			(end 1.8288 -2.500122)
			(stroke
				(width 0.1524)
				(type default)
			)
			(layer "F.SilkS")
		)
		(fp_poly
			(pts
				(xy -4.358386 -2.450592) (xy -4.358386 -1.434592) (xy -3.342386 -1.942592)
			)
			(stroke
				(width 0)
				(type default)
			)
			(fill yes)
			(layer "F.SilkS")
		)
		(fp_poly
			(pts
				(xy -1.999996 -2.500122) (xy -1.999996 -2.413) (xy -3.302 -2.413) (xy -3.302 2.413) (xy -1.999996 2.413)
				(xy -1.999996 2.500122) (xy 1.999996 2.500122) (xy 1.999996 2.413) (xy 3.302 2.413) (xy 3.302 -2.413)
				(xy 1.999996 -2.413) (xy 1.999996 -2.500122)
			)
			(stroke
				(width 0)
				(type default)
			)
			(fill no)
			(layer "F.CrtYd")
		)
		(fp_line
			(start -1.999996 -2.500122)
			(end -1.999996 2.500122)
			(stroke
				(width 0.1)
				(type default)
			)
			(layer "F.Fab")
		)
		(fp_line
			(start -1.999996 2.500122)
			(end 1.999996 2.500122)
			(stroke
				(width 0.1)
				(type default)
			)
			(layer "F.Fab")
		)
		(fp_line
			(start 1.999996 -2.500122)
			(end -1.999996 -2.500122)
			(stroke
				(width 0.1)
				(type default)
			)
			(layer "F.Fab")
		)
		(fp_line
			(start 1.999996 2.500122)
			(end 1.999996 -2.500122)
			(stroke
				(width 0.1)
				(type default)
			)
			(layer "F.Fab")
		)
		(fp_poly
			(pts
				(xy -4.5085 -2.413) (xy -4.5085 -1.397) (xy -3.4925 -1.905)
			)
			(stroke
				(width 0)
				(type default)
			)
			(fill yes)
			(layer "F.Fab")
		)
		(pad "1" smd rect
			(at -2.599944 -1.905 270)
			(size 0.889 1.27)
			(layers "F.Cu" "F.Mask" "F.Paste")
			(net "FRU_A0")
		)
		(pad "2" smd rect
			(at -2.599944 -0.635 270)
			(size 0.889 1.27)
			(layers "F.Cu" "F.Mask" "F.Paste")
			(net "FRU_A1")
		)
		(pad "3" smd rect
			(at -2.599944 0.635 270)
			(size 0.889 1.27)
			(layers "F.Cu" "F.Mask" "F.Paste")
			(net "FRU_A2")
		)
		(pad "4" smd rect
			(at -2.599944 1.905 270)
			(size 0.889 1.27)
			(layers "F.Cu" "F.Mask" "F.Paste")
			(net "GND")
		)
		(pad "5" smd rect
			(at 2.599944 1.905 270)
			(size 0.889 1.27)
			(layers "F.Cu" "F.Mask" "F.Paste")
			(net "I2C_PDB_SDA")
		)
		(pad "6" smd rect
			(at 2.599944 0.635 270)
			(size 0.889 1.27)
			(layers "F.Cu" "F.Mask" "F.Paste")
			(net "I2C_PDB_SCL")
		)
		(pad "7" smd rect
			(at 2.599944 -0.635 270)
			(size 0.889 1.27)
			(layers "F.Cu" "F.Mask" "F.Paste")
			(net "FRU_WP")
		)
		(pad "8" smd rect
			(at 2.599944 -1.905 270)
			(size 0.889 1.27)
			(layers "F.Cu" "F.Mask" "F.Paste")
			(net "P3V3")
		)
	)
	(footprint ""
		(layer "F.Cu")
		(at 27.640026 -284.62986 90)
		(property "Reference" "R125"
			(at -3.83413 -1.65354 90)
			(unlocked yes)
			(layer "F.SilkS")
			(effects
				(font
					(size 0.7874 0.5842)
					(thickness 0.1524)
				)
				(justify left)
			)
		)
		(property "Value" ""
			(at 0 0 90)
			(layer "F.Fab")
			(effects
				(font
					(size 1.27 1.27)
				)
			)
		)
		(duplicate_pad_numbers_are_jumpers no)
		(fp_line
			(start 0.7874 -0.4064)
			(end 0.7874 0.4064)
			(stroke
				(width 0.1524)
				(type default)
			)
			(layer "F.SilkS")
		)
		(fp_line
			(start -0.7874 -0.4064)
			(end 0.7874 -0.4064)
			(stroke
				(width 0.1524)
				(type default)
			)
			(layer "F.SilkS")
		)
		(fp_line
			(start 0.7874 0.4064)
			(end -0.7874 0.4064)
			(stroke
				(width 0.1524)
				(type default)
			)
			(layer "F.SilkS")
		)
		(fp_line
			(start -0.7874 0.4064)
			(end -0.7874 -0.4064)
			(stroke
				(width 0.1524)
				(type default)
			)
			(layer "F.SilkS")
		)
		(fp_poly
			(pts
				(xy -0.508 0.2794) (xy -0.508 0.2286) (xy -0.635 0.2286) (xy -0.635 -0.254) (xy -0.5334 -0.254)
				(xy -0.5334 -0.2794) (xy 0.5334 -0.2794) (xy 0.5334 -0.254) (xy 0.635 -0.254) (xy 0.635 0.254) (xy 0.5334 0.254)
				(xy 0.5334 0.2794)
			)
			(stroke
				(width 0)
				(type default)
			)
			(fill no)
			(layer "F.CrtYd")
		)
		(pad "1" smd rect
			(at 0.40005 0 90)
			(size 0.4572 0.508)
			(layers "F.Cu" "F.Mask" "F.Paste")
			(net "PSU4_REMOTE_N")
		)
		(pad "2" smd rect
			(at -0.40005 0 90)
			(size 0.4572 0.508)
			(layers "F.Cu" "F.Mask" "F.Paste")
			(net "PSU4_REMOTE_R2_N")
		)
	)
)
